(kicad_pcb
	(version 20260206)
	(generator "pcbnew")
	(generator_version "10.0")
	(general
		(thickness 1.6)
		(legacy_teardrops no)
	)
	(paper "A4")
	(title_block
		(title "Wiwynn_Tioga_Pass_MB.brd")
		(comment 1 "Tioga Pass / footprints 1536-1542 of 4770")
	)
	(layers
		(0 "F.Cu" signal "TOP")
		(4 "In1.Cu" signal "L2GND")
		(6 "In2.Cu" signal "L3")
		(8 "In3.Cu" signal "L4GND")
		(10 "In4.Cu" signal "L5")
		(12 "In5.Cu" signal "L6GND")
		(14 "In6.Cu" signal "L7VCC")
		(16 "In7.Cu" signal "L8VCC")
		(18 "In8.Cu" signal "L9GND")
		(20 "In9.Cu" signal "L10")
		(22 "In10.Cu" signal "L11GND")
		(24 "In11.Cu" signal "L12")
		(26 "In12.Cu" signal "L13GND")
		(2 "B.Cu" signal "BOTTOM")
		(9 "F.Adhes" user "F.Adhesive")
		(11 "B.Adhes" user "B.Adhesive")
		(13 "F.Paste" user "Package Geometry/Pastemask Top")
		(15 "B.Paste" user "Package Geometry/Pastemask Bottom")
		(5 "F.SilkS" user "Ref Des/Silkscreen Top")
		(7 "B.SilkS" user "Ref Des/Silkscreen Bottom")
		(1 "F.Mask" user "Board Geometry/Soldermask Top")
		(3 "B.Mask" user "Board Geometry/Soldermask Bottom")
		(17 "Dwgs.User" user "User.Drawings")
		(19 "Cmts.User" user "User.Comments")
		(21 "Eco1.User" user "User.Eco1")
		(23 "Eco2.User" user "User.Eco2")
		(25 "Edge.Cuts" user "Board Geometry/Outline")
		(27 "Margin" user)
		(31 "F.CrtYd" user "Package Geometry/Place Bound Top")
		(29 "B.CrtYd" user "Package Geometry/Place Bound Bottom")
		(35 "F.Fab" user "Ref Des/Assembly Top")
		(33 "B.Fab" user "Ref Des/Assembly Bottom")
	)
	(footprint ""
		(layer "F.Cu")
		(at 38.07968 -34.912808)
		(property "Reference" "CR1F5"
			(at 4.29133 1.397 270)
			(unlocked yes)
			(layer "F.SilkS")
			(effects
				(font
					(size 0.7874 0.5842)
					(thickness 0.1524)
				)
				(justify left)
			)
		)
		(property "Value" ""
			(at 0 0 0)
			(layer "F.Fab")
			(effects
				(font
					(size 1.27 1.27)
				)
			)
		)
		(duplicate_pad_numbers_are_jumpers no)
		(fp_line
			(start -3.111754 7.5946)
			(end -3.1115 -0.228346)
			(stroke
				(width 0.1524)
				(type default)
			)
			(layer "F.SilkS")
		)
		(fp_line
			(start -3.111754 7.5946)
			(end -1.9431 7.5946)
			(stroke
				(width 0.1524)
				(type default)
			)
			(layer "F.SilkS")
		)
		(fp_line
			(start -3.1115 -0.228346)
			(end -1.9431 -0.2286)
			(stroke
				(width 0.1524)
				(type default)
			)
			(layer "F.SilkS")
		)
		(fp_line
			(start 1.9431 -0.2286)
			(end 3.1115 -0.228346)
			(stroke
				(width 0.1524)
				(type default)
			)
			(layer "F.SilkS")
		)
		(fp_line
			(start 1.9431 7.5946)
			(end 3.111754 7.5946)
			(stroke
				(width 0.1524)
				(type default)
			)
			(layer "F.SilkS")
		)
		(fp_line
			(start 3.1115 -0.228346)
			(end 3.111754 7.5946)
			(stroke
				(width 0.1524)
				(type default)
			)
			(layer "F.SilkS")
		)
		(fp_circle
			(center -2.413 -1.016)
			(end -2.286 -1.016)
			(stroke
				(width 0.254)
				(type default)
			)
			(fill no)
			(layer "F.SilkS")
		)
		(fp_poly
			(pts
				(xy -3.111754 7.5946) (xy 3.111754 7.5946) (xy 3.1115 -0.228346) (xy -3.1115 -0.228346)
			)
			(stroke
				(width 0)
				(type default)
			)
			(fill no)
			(layer "F.CrtYd")
		)
		(fp_line
			(start -3.111754 7.5946)
			(end 3.111754 7.5946)
			(stroke
				(width 0.1)
				(type default)
			)
			(layer "F.Fab")
		)
		(fp_line
			(start -3.1115 -0.228346)
			(end -3.111754 7.5946)
			(stroke
				(width 0.1)
				(type default)
			)
			(layer "F.Fab")
		)
		(fp_line
			(start 3.1115 -0.228346)
			(end -3.1115 -0.228346)
			(stroke
				(width 0.1)
				(type default)
			)
			(layer "F.Fab")
		)
		(fp_line
			(start 3.111754 7.5946)
			(end 3.1115 -0.228346)
			(stroke
				(width 0.1)
				(type default)
			)
			(layer "F.Fab")
		)
		(fp_circle
			(center -2.413 -0.9906)
			(end -2.286 -0.9906)
			(stroke
				(width 0.254)
				(type default)
			)
			(fill no)
			(layer "F.Fab")
		)
		(pad "1" smd rect
			(at 0 0)
			(size 3.048 2.286)
			(layers "F.Cu" "F.Mask" "F.Paste")
			(net "P12V_STBY")
		)
		(pad "2" smd rect
			(at 0 7.366)
			(size 3.048 2.286)
			(layers "F.Cu" "F.Mask" "F.Paste")
			(net "GND")
		)
	)
	(footprint ""
		(layer "F.Cu")
		(at 417.83 -56.2229)
		(property "Reference" "C8E8"
			(at 0 0 0)
			(layer "F.SilkS")
			(hide yes)
			(effects
				(font
					(size 1.27 1.27)
				)
			)
		)
		(property "Value" ""
			(at 0 0 0)
			(layer "F.Fab")
			(effects
				(font
					(size 1.27 1.27)
				)
			)
		)
		(duplicate_pad_numbers_are_jumpers no)
		(fp_poly
			(pts
				(xy 0.3048 -0.1016) (xy 0.3048 0.9906) (xy -0.3048 0.9906) (xy -0.3048 -0.1016)
			)
			(stroke
				(width 0)
				(type default)
			)
			(fill no)
			(layer "F.CrtYd")
		)
		(fp_line
			(start -0.3048 -0.1016)
			(end -0.3048 0.9906)
			(stroke
				(width 0.1)
				(type default)
			)
			(layer "F.Fab")
		)
		(fp_line
			(start -0.3048 0.9906)
			(end 0.3048 0.9906)
			(stroke
				(width 0.1)
				(type default)
			)
			(layer "F.Fab")
		)
		(fp_line
			(start 0.3048 -0.1016)
			(end -0.3048 -0.1016)
			(stroke
				(width 0.1)
				(type default)
			)
			(layer "F.Fab")
		)
		(fp_line
			(start 0.3048 0.9906)
			(end 0.3048 -0.1016)
			(stroke
				(width 0.1)
				(type default)
			)
			(layer "F.Fab")
		)
		(pad "1" smd rect
			(at 0 0)
			(size 0.508 0.508)
			(layers "F.Cu" "F.Mask" "F.Paste")
			(net "P3V3_STBY")
		)
		(pad "2" smd rect
			(at 0 0.889)
			(size 0.508 0.508)
			(layers "F.Cu" "F.Mask" "F.Paste")
			(net "GND")
		)
		(zone
			(layer "F.Cu")
			(hatch none 0.5)
			(connect_pads
				(clearance 0)
			)
			(min_thickness 0.25)
			(keepout
				(tracks allowed)
				(vias not_allowed)
				(pads allowed)
				(copperpour not_allowed)
				(footprints allowed)
			)
			(placement
				(enabled no)
				(sheetname "")
			)
			(fill
				(thermal_gap 0.5)
				(thermal_bridge_width 0.5)
				(island_removal_mode 0)
			)
			(polygon
				(pts
					(xy 417.576 -55.9689) (xy 418.084 -55.9689) (xy 418.084 -55.5879) (xy 417.576 -55.5879)
				)
			)
		)
		(zone
			(layer "F.Cu")
			(hatch none 0.5)
			(connect_pads
				(clearance 0)
			)
			(min_thickness 0.25)
			(keepout
				(tracks not_allowed)
				(vias allowed)
				(pads allowed)
				(copperpour not_allowed)
				(footprints allowed)
			)
			(placement
				(enabled no)
				(sheetname "")
			)
			(fill
				(thermal_gap 0.5)
				(thermal_bridge_width 0.5)
				(island_removal_mode 0)
			)
			(polygon
				(pts
					(xy 417.576 -55.5879) (xy 418.084 -55.5879) (xy 418.084 -55.9689) (xy 417.576 -55.9689)
				)
			)
		)
	)
	(footprint ""
		(layer "F.Cu")
		(at 479.806 -145.288)
		(property "Reference" "U9A3"
			(at 0 0 0)
			(layer "F.SilkS")
			(hide yes)
			(effects
				(font
					(size 1.27 1.27)
				)
			)
		)
		(property "Value" "*"
			(at -2.3622 -8.3185 0)
			(unlocked yes)
			(layer "F.Fab")
			(hide yes)
			(effects
				(font
					(size 1.27 1.016)
					(thickness 0.1524)
				)
			)
		)
		(property "Device Type" "TC7PZ14FU-GP_DISCRET-GA1-TC7PZA"
			(at -2.3622 -10.2235 0)
			(unlocked yes)
			(layer "F.Fab")
			(hide yes)
			(effects
				(font
					(size 1.27 1.016)
					(thickness 0.1524)
				)
			)
		)
		(duplicate_pad_numbers_are_jumpers no)
		(fp_line
			(start -1.5494 1.7907)
			(end -1.5494 0.8255)
			(stroke
				(width 0.3302)
				(type default)
			)
			(layer "F.SilkS")
		)
		(fp_line
			(start -1.4478 -1.7018)
			(end -1.4478 1.7018)
			(stroke
				(width 0.1524)
				(type default)
			)
			(layer "F.SilkS")
		)
		(fp_line
			(start -1.4478 1.7018)
			(end 1.4478 1.7018)
			(stroke
				(width 0.1524)
				(type default)
			)
			(layer "F.SilkS")
		)
		(fp_line
			(start -0.5715 1.7907)
			(end -1.5494 1.7907)
			(stroke
				(width 0.3302)
				(type default)
			)
			(layer "F.SilkS")
		)
		(fp_line
			(start 1.4478 -1.7018)
			(end -1.4478 -1.7018)
			(stroke
				(width 0.1524)
				(type default)
			)
			(layer "F.SilkS")
		)
		(fp_line
			(start 1.4478 1.7018)
			(end 1.4478 -1.7018)
			(stroke
				(width 0.1524)
				(type default)
			)
			(layer "F.SilkS")
		)
		(fp_poly
			(pts
				(xy -0.6604 1.7272) (xy -1.016 2.0828) (xy -0.3048 2.0828)
			)
			(stroke
				(width 0)
				(type default)
			)
			(fill yes)
			(layer "F.SilkS")
		)
		(fp_poly
			(pts
				(xy -1.524 -1.778) (xy 1.524 -1.778) (xy 1.524 1.778) (xy -1.524 1.778)
			)
			(stroke
				(width 0)
				(type default)
			)
			(fill no)
			(layer "F.CrtYd")
		)
		(fp_poly
			(pts
				(xy -1.524 -1.778) (xy 1.524 -1.778) (xy 1.524 1.778) (xy -1.524 1.778)
			)
			(stroke
				(width 0)
				(type default)
			)
			(fill no)
			(layer "F.Fab")
		)
		(pad "1" smd rect
			(at -0.65024 0.9398)
			(size 0.4064 1.016)
			(layers "F.Cu" "F.Mask" "F.Paste")
			(net "FP_RST_BTN_R_N")
		)
		(pad "2" smd rect
			(at 0 0.9398)
			(size 0.4064 1.016)
			(layers "F.Cu" "F.Mask" "F.Paste")
			(net "GND")
		)
		(pad "3" smd rect
			(at 0.65024 0.9398)
			(size 0.4064 1.016)
			(layers "F.Cu" "F.Mask" "F.Paste")
			(net "FP_RST_BTN_BUF1_N")
		)
		(pad "4" smd rect
			(at 0.65024 -0.9398)
			(size 0.4064 1.016)
			(layers "F.Cu" "F.Mask" "F.Paste")
			(net "RST_SYSTEM_BTN_BUF_N")
		)
		(pad "5" smd rect
			(at 0 -0.9398)
			(size 0.4064 1.016)
			(layers "F.Cu" "F.Mask" "F.Paste")
			(net "P3V3_STBY")
		)
		(pad "6" smd rect
			(at -0.65024 -0.9398)
			(size 0.4064 1.016)
			(layers "F.Cu" "F.Mask" "F.Paste")
			(net "FP_RST_BTN_BUF1_N")
		)
	)
	(footprint ""
		(layer "F.Cu")
		(at 97.132902 -83.84159)
		(property "Reference" "C2D8"
			(at 0 0 0)
			(layer "F.SilkS")
			(hide yes)
			(effects
				(font
					(size 1.27 1.27)
				)
			)
		)
		(property "Value" ""
			(at 0 0 0)
			(layer "F.Fab")
			(effects
				(font
					(size 1.27 1.27)
				)
			)
		)
		(duplicate_pad_numbers_are_jumpers no)
		(fp_poly
			(pts
				(xy -0.4953 -0.2032) (xy 0.4953 -0.2032) (xy 0.4953 1.6002) (xy -0.4953 1.6002)
			)
			(stroke
				(width 0)
				(type default)
			)
			(fill no)
			(layer "F.CrtYd")
		)
		(fp_line
			(start -0.4953 -0.2032)
			(end 0.4953 -0.2032)
			(stroke
				(width 0.1)
				(type default)
			)
			(layer "F.Fab")
		)
		(fp_line
			(start -0.4953 1.6002)
			(end -0.4953 -0.2032)
			(stroke
				(width 0.1)
				(type default)
			)
			(layer "F.Fab")
		)
		(fp_line
			(start 0.4953 -0.2032)
			(end 0.4953 1.6002)
			(stroke
				(width 0.1)
				(type default)
			)
			(layer "F.Fab")
		)
		(fp_line
			(start 0.4953 1.6002)
			(end -0.4953 1.6002)
			(stroke
				(width 0.1)
				(type default)
			)
			(layer "F.Fab")
		)
		(pad "1" smd rect
			(at 0 0)
			(size 0.762 0.889)
			(layers "F.Cu" "F.Mask" "F.Paste")
			(net "PVSA_CPU1")
		)
		(pad "2" smd rect
			(at 0 1.397)
			(size 0.762 0.889)
			(layers "F.Cu" "F.Mask" "F.Paste")
			(net "GND")
		)
		(zone
			(layer "F.Cu")
			(hatch none 0.5)
			(connect_pads
				(clearance 0)
			)
			(min_thickness 0.25)
			(keepout
				(tracks not_allowed)
				(vias allowed)
				(pads allowed)
				(copperpour not_allowed)
				(footprints allowed)
			)
			(placement
				(enabled no)
				(sheetname "")
			)
			(fill
				(thermal_gap 0.5)
				(thermal_bridge_width 0.5)
				(island_removal_mode 0)
			)
			(polygon
				(pts
					(xy 96.751902 -83.39709) (xy 97.513902 -83.39709) (xy 97.513902 -82.88909) (xy 96.751902 -82.88909)
				)
			)
		)
	)
	(footprint ""
		(layer "F.Cu")
		(at 473.075 -148.0185 180)
		(property "Reference" "R9A12"
			(at 0 0 180)
			(layer "F.SilkS")
			(hide yes)
			(effects
				(font
					(size 1.27 1.27)
				)
			)
		)
		(property "Value" ""
			(at 0 0 180)
			(layer "F.Fab")
			(effects
				(font
					(size 1.27 1.27)
				)
			)
		)
		(duplicate_pad_numbers_are_jumpers no)
		(fp_poly
			(pts
				(xy -0.2794 -0.1016) (xy 0.2794 -0.1016) (xy 0.2794 0.9906) (xy -0.2794 0.9906)
			)
			(stroke
				(width 0)
				(type default)
			)
			(fill no)
			(layer "F.CrtYd")
		)
		(fp_line
			(start 0.2794 0.9906)
			(end 0.2794 -0.1016)
			(stroke
				(width 0.1)
				(type default)
			)
			(layer "F.Fab")
		)
		(fp_line
			(start 0.2794 -0.1016)
			(end -0.2794 -0.1016)
			(stroke
				(width 0.1)
				(type default)
			)
			(layer "F.Fab")
		)
		(fp_line
			(start -0.2794 0.9906)
			(end 0.2794 0.9906)
			(stroke
				(width 0.1)
				(type default)
			)
			(layer "F.Fab")
		)
		(fp_line
			(start -0.2794 -0.1016)
			(end -0.2794 0.9906)
			(stroke
				(width 0.1)
				(type default)
			)
			(layer "F.Fab")
		)
		(pad "1" smd rect
			(at 0 0 180)
			(size 0.508 0.508)
			(layers "F.Cu" "F.Mask" "F.Paste")
			(net "FM_PCH_SATA_RAID_KEY_R")
		)
		(pad "2" smd rect
			(at 0 0.889 180)
			(size 0.508 0.508)
			(layers "F.Cu" "F.Mask" "F.Paste")
			(net "P3V3_STBY")
		)
		(zone
			(layer "F.Cu")
			(hatch none 0.5)
			(connect_pads
				(clearance 0)
			)
			(min_thickness 0.25)
			(keepout
				(tracks not_allowed)
				(vias allowed)
				(pads allowed)
				(copperpour not_allowed)
				(footprints allowed)
			)
			(placement
				(enabled no)
				(sheetname "")
			)
			(fill
				(thermal_gap 0.5)
				(thermal_bridge_width 0.5)
				(island_removal_mode 0)
			)
			(polygon
				(pts
					(xy 473.329 -148.6535) (xy 472.821 -148.6535) (xy 472.821 -148.2725) (xy 473.329 -148.2725)
				)
			)
		)
		(zone
			(layer "F.Cu")
			(hatch none 0.5)
			(connect_pads
				(clearance 0)
			)
			(min_thickness 0.25)
			(keepout
				(tracks allowed)
				(vias not_allowed)
				(pads allowed)
				(copperpour not_allowed)
				(footprints allowed)
			)
			(placement
				(enabled no)
				(sheetname "")
			)
			(fill
				(thermal_gap 0.5)
				(thermal_bridge_width 0.5)
				(island_removal_mode 0)
			)
			(polygon
				(pts
					(xy 473.329 -148.2725) (xy 472.821 -148.2725) (xy 472.821 -148.6535) (xy 473.329 -148.6535)
				)
			)
		)
	)
	(footprint ""
		(layer "F.Cu")
		(at 449.69938 -31.3055 90)
		(property "Reference" "R25W8"
			(at 0 0 90)
			(layer "F.SilkS")
			(hide yes)
			(effects
				(font
					(size 1.27 1.27)
				)
			)
		)
		(property "Value" "*"
			(at 0.064008 -4.108196 90)
			(unlocked yes)
			(layer "F.Fab")
			(hide yes)
			(effects
				(font
					(size 1.27 1.016)
					(thickness 0.1524)
				)
			)
		)
		(property "Device Type" "120R2F-GP_RCL_GP-120R2F-GP,64.A"
			(at 0.064008 -5.632196 90)
			(unlocked yes)
			(layer "F.Fab")
			(hide yes)
			(effects
				(font
					(size 1.27 1.016)
					(thickness 0.1524)
				)
			)
		)
		(duplicate_pad_numbers_are_jumpers no)
		(fp_line
			(start 0.508 -0.9398)
			(end -0.508 -0.9398)
			(stroke
				(width 0.1524)
				(type default)
			)
			(layer "F.SilkS")
		)
		(fp_line
			(start -0.508 -0.9398)
			(end -0.508 0.9398)
			(stroke
				(width 0.1524)
				(type default)
			)
			(layer "F.SilkS")
		)
		(fp_rect
			(start -0.508 0.9398)
			(end 0.508 -0.9398)
			(stroke
				(width 0)
				(type default)
			)
			(fill no)
			(layer "F.CrtYd")
		)
		(fp_rect
			(start -0.508 0.9398)
			(end 0.508 -0.9398)
			(stroke
				(width 0)
				(type default)
			)
			(fill no)
			(layer "F.Fab")
		)
		(pad "1" smd custom
			(at 0 -0.4445 90)
			(size 0.1397 0.1397)
			(layers "F.Cu" "F.Mask" "F.Paste")
			(net "GND")
			(options
				(clearance outline)
				(anchor circle)
			)
			(primitives
				(gr_poly
					(pts
						(arc
							(start -0.1778 -0.2794)
							(mid -0.249642 -0.249642)
							(end -0.2794 -0.1778)
						)
						(arc
							(start -0.2794 0.1778)
							(mid -0.249642 0.249642)
							(end -0.1778 0.2794)
						)
						(arc
							(start 0.1778 0.2794)
							(mid 0.249642 0.249642)
							(end 0.2794 0.1778)
						)
						(arc
							(start 0.2794 -0.1778)
							(mid 0.249642 -0.249642)
							(end 0.1778 -0.2794)
						)
					)
					(width 0)
					(fill yes)
				)
			)
		)
		(pad "2" smd custom
			(at 0 0.4445 90)
			(size 0.1397 0.1397)
			(layers "F.Cu" "F.Mask" "F.Paste")
			(net "BMC_M_WE_N")
			(options
				(clearance outline)
				(anchor circle)
			)
			(primitives
				(gr_poly
					(pts
						(arc
							(start -0.1778 -0.2794)
							(mid -0.249642 -0.249642)
							(end -0.2794 -0.1778)
						)
						(arc
							(start -0.2794 0.1778)
							(mid -0.249642 0.249642)
							(end -0.1778 0.2794)
						)
						(arc
							(start 0.1778 0.2794)
							(mid 0.249642 0.249642)
							(end 0.2794 0.1778)
						)
						(arc
							(start 0.2794 -0.1778)
							(mid 0.249642 -0.249642)
							(end 0.1778 -0.2794)
						)
					)
					(width 0)
					(fill yes)
				)
			)
		)
	)
	(footprint ""
		(layer "F.Cu")
		(at 368.554 -113.792 90)
		(property "Reference" "C7B27"
			(at 0 0 90)
			(layer "F.SilkS")
			(hide yes)
			(effects
				(font
					(size 1.27 1.27)
				)
			)
		)
		(property "Value" ""
			(at 0 0 90)
			(layer "F.Fab")
			(effects
				(font
					(size 1.27 1.27)
				)
			)
		)
		(duplicate_pad_numbers_are_jumpers no)
		(fp_poly
			(pts
				(xy 0.3048 -0.1016) (xy 0.3048 0.9906) (xy -0.3048 0.9906) (xy -0.3048 -0.1016)
			)
			(stroke
				(width 0)
				(type default)
			)
			(fill no)
			(layer "F.CrtYd")
		)
		(fp_line
			(start 0.3048 -0.1016)
			(end -0.3048 -0.1016)
			(stroke
				(width 0.1)
				(type default)
			)
			(layer "F.Fab")
		)
		(fp_line
			(start -0.3048 -0.1016)
			(end -0.3048 0.9906)
			(stroke
				(width 0.1)
				(type default)
			)
			(layer "F.Fab")
		)
		(fp_line
			(start 0.3048 0.9906)
			(end 0.3048 -0.1016)
			(stroke
				(width 0.1)
				(type default)
			)
			(layer "F.Fab")
		)
		(fp_line
			(start -0.3048 0.9906)
			(end 0.3048 0.9906)
			(stroke
				(width 0.1)
				(type default)
			)
			(layer "F.Fab")
		)
		(pad "1" smd rect
			(at 0 0 90)
			(size 0.508 0.508)
			(layers "F.Cu" "F.Mask" "F.Paste")
			(net "DMI_CPU0_PCH_TX_DP<2>")
		)
		(pad "2" smd rect
			(at 0 0.889 90)
			(size 0.508 0.508)
			(layers "F.Cu" "F.Mask" "F.Paste")
			(net "DMI_CPU0_PCH_TX_C_DP<2>")
		)
		(zone
			(layer "F.Cu")
			(hatch none 0.5)
			(connect_pads
				(clearance 0)
			)
			(min_thickness 0.25)
			(keepout
				(tracks allowed)
				(vias not_allowed)
				(pads allowed)
				(copperpour not_allowed)
				(footprints allowed)
			)
			(placement
				(enabled no)
				(sheetname "")
			)
			(fill
				(thermal_gap 0.5)
				(thermal_bridge_width 0.5)
				(island_removal_mode 0)
			)
			(polygon
				(pts
					(xy 368.808 -113.538) (xy 368.808 -114.046) (xy 369.189 -114.046) (xy 369.189 -113.538)
				)
			)
		)
		(zone
			(layer "F.Cu")
			(hatch none 0.5)
			(connect_pads
				(clearance 0)
			)
			(min_thickness 0.25)
			(keepout
				(tracks not_allowed)
				(vias allowed)
				(pads allowed)
				(copperpour not_allowed)
				(footprints allowed)
			)
			(placement
				(enabled no)
				(sheetname "")
			)
			(fill
				(thermal_gap 0.5)
				(thermal_bridge_width 0.5)
				(island_removal_mode 0)
			)
			(polygon
				(pts
					(xy 369.189 -113.538) (xy 369.189 -114.046) (xy 368.808 -114.046) (xy 368.808 -113.538)
				)
			)
		)
	)
)
